# S9S_MB_2U (Grand Teton) — schematic netlist excerpt (pin names and nets, part order shuffled) for the footprints in the layout excerpt that follows; sources: Cadence DE-HDL packaged netlist, KiCad conversion of 03242023_DA0F0TMBIJ0_F0T_Motherboard_J_brd_V01_OCP.brd

PC175  Q_CAP  2.2UF 10V 10% X6S  pkg C0402  page 276 : A = PVCCFA_EHV_CPU0_VDD1 ; B = GND
PC2154  Q_CAP  1UF 25V 10% X6S  pkg C0402  page 157 : A = P12V_AUX ; B = GND
C1560  Q_CAP_DIFFBUS  DIFF BUS_0.22UF 6.3V 20% X6S  pkg C0201  page 175 : \1\ = P5E_CPU0_PE4_TX_C_DN<9> ; \2\ = P5E_CPU0_PE4_TX_DN<9>

(kicad_pcb
	(version 20260206)
	(generator "pcbnew")
	(generator_version "10.0")
	(general
		(thickness 1.6)
		(legacy_teardrops no)
	)
	(paper "A4")
	(title_block
		(title "03242023_DA0F0TMBIJ0_F0T_Motherboard_J_brd_V01_OCP.brd")
		(comment 1 "Grand Teton / footprints 1835-1837 of 6105")
	)
	(layers
		(0 "F.Cu" signal "TOP")
		(4 "In1.Cu" signal "GND")
		(6 "In2.Cu" signal "IN1")
		(8 "In3.Cu" signal "GND1")
		(10 "In4.Cu" signal "IN2")
		(12 "In5.Cu" signal "GND2")
		(14 "In6.Cu" signal "IN3")
		(16 "In7.Cu" signal "GND3")
		(18 "In8.Cu" signal "VCC")
		(20 "In9.Cu" signal "VCC1")
		(22 "In10.Cu" signal "GND4")
		(24 "In11.Cu" signal "IN4")
		(26 "In12.Cu" signal "GND5")
		(28 "In13.Cu" signal "IN5")
		(30 "In14.Cu" signal "GND6")
		(32 "In15.Cu" signal "IN6")
		(34 "In16.Cu" signal "GND7")
		(2 "B.Cu" signal "BOTTOM")
		(9 "F.Adhes" user "F.Adhesive")
		(11 "B.Adhes" user "B.Adhesive")
		(13 "F.Paste" user "Package Geometry/Pastemask Top")
		(15 "B.Paste" user "Package Geometry/Pastemask Bottom")
		(5 "F.SilkS" user "Ref Des/Silkscreen Top")
		(7 "B.SilkS" user "Ref Des/Silkscreen Bottom")
		(1 "F.Mask" user "Board Geometry/Soldermask Top")
		(3 "B.Mask" user "Board Geometry/Soldermask Bottom")
		(17 "Dwgs.User" user "User.Drawings")
		(19 "Cmts.User" user "User.Comments")
		(21 "Eco1.User" user "User.Eco1")
		(23 "Eco2.User" user "User.Eco2")
		(25 "Edge.Cuts" user "Board Geometry/Outline")
		(27 "Margin" user)
		(31 "F.CrtYd" user "Package Geometry/Place Bound Top")
		(29 "B.CrtYd" user "Package Geometry/Place Bound Bottom")
		(35 "F.Fab" user "Ref Des/Assembly Top")
		(33 "B.Fab" user "Ref Des/Assembly Bottom")
	)
	(footprint ""
		(layer "F.Cu")
		(at 448.177412 -30.131258 90)
		(property "Reference" "PC2154"
			(at 0 0 90)
			(layer "F.SilkS")
			(hide yes)
			(effects
				(font
					(size 1.27 1.27)
				)
			)
		)
		(property "Value" ""
			(at 0 0 90)
			(layer "F.Fab")
			(effects
				(font
					(size 1.27 1.27)
				)
			)
		)
		(duplicate_pad_numbers_are_jumpers no)
		(fp_line
			(start 0.7874 -0.4064)
			(end 0.7874 0.4064)
			(stroke
				(width 0.1524)
				(type default)
			)
			(layer "F.SilkS")
		)
		(fp_line
			(start -0.7874 -0.4064)
			(end 0.7874 -0.4064)
			(stroke
				(width 0.1524)
				(type default)
			)
			(layer "F.SilkS")
		)
		(fp_line
			(start 0.7874 0.4064)
			(end -0.7874 0.4064)
			(stroke
				(width 0.1524)
				(type default)
			)
			(layer "F.SilkS")
		)
		(fp_line
			(start -0.7874 0.4064)
			(end -0.7874 -0.4064)
			(stroke
				(width 0.1524)
				(type default)
			)
			(layer "F.SilkS")
		)
		(fp_line
			(start -0.12065 -0.305054)
			(end -0.12065 -0.2794)
			(stroke
				(width 0.1)
				(type default)
			)
			(layer "F.Fab")
		)
		(fp_line
			(start -0.67945 -0.305054)
			(end -0.12065 -0.305054)
			(stroke
				(width 0.1)
				(type default)
			)
			(layer "F.Fab")
		)
		(fp_line
			(start 0.67945 -0.3048)
			(end 0.67945 0.3048)
			(stroke
				(width 0.1)
				(type default)
			)
			(layer "F.Fab")
		)
		(fp_line
			(start 0.12065 -0.3048)
			(end 0.67945 -0.3048)
			(stroke
				(width 0.1)
				(type default)
			)
			(layer "F.Fab")
		)
		(fp_line
			(start 0.12065 -0.2794)
			(end 0.12065 -0.3048)
			(stroke
				(width 0.1)
				(type default)
			)
			(layer "F.Fab")
		)
		(fp_line
			(start -0.12065 -0.2794)
			(end 0.12065 -0.2794)
			(stroke
				(width 0.1)
				(type default)
			)
			(layer "F.Fab")
		)
		(fp_line
			(start 0.120396 0.2794)
			(end -0.12065 0.2794)
			(stroke
				(width 0.1)
				(type default)
			)
			(layer "F.Fab")
		)
		(fp_line
			(start -0.12065 0.2794)
			(end -0.12065 0.3048)
			(stroke
				(width 0.1)
				(type default)
			)
			(layer "F.Fab")
		)
		(fp_line
			(start 0.67945 0.3048)
			(end 0.120396 0.3048)
			(stroke
				(width 0.1)
				(type default)
			)
			(layer "F.Fab")
		)
		(fp_line
			(start 0.120396 0.3048)
			(end 0.120396 0.2794)
			(stroke
				(width 0.1)
				(type default)
			)
			(layer "F.Fab")
		)
		(fp_line
			(start -0.12065 0.3048)
			(end -0.67945 0.3048)
			(stroke
				(width 0.1)
				(type default)
			)
			(layer "F.Fab")
		)
		(fp_line
			(start -0.67945 0.3048)
			(end -0.67945 -0.305054)
			(stroke
				(width 0.1)
				(type default)
			)
			(layer "F.Fab")
		)
		(pad "1" smd circle
			(at -0.40005 0 90)
			(size 0 0)
			(layers "F.Cu" "F.Mask" "F.Paste")
			(net "P12V_AUX")
		)
		(pad "2" smd circle
			(at 0.40005 0 90)
			(size 0 0)
			(layers "F.Cu" "F.Mask" "F.Paste")
			(net "GND")
		)
	)
	(footprint ""
		(layer "F.Cu")
		(at 331.523848 -402.371052 -90)
		(property "Reference" "C1560"
			(at 0 0 270)
			(layer "F.SilkS")
			(hide yes)
			(effects
				(font
					(size 1.27 1.27)
				)
			)
		)
		(property "Value" ""
			(at 0 0 270)
			(layer "F.Fab")
			(effects
				(font
					(size 1.27 1.27)
				)
			)
		)
		(duplicate_pad_numbers_are_jumpers no)
		(fp_line
			(start -0.299974 0.150114)
			(end -0.299974 -0.150114)
			(stroke
				(width 0.1)
				(type default)
			)
			(layer "F.Fab")
		)
		(fp_line
			(start 0.299974 0.150114)
			(end -0.299974 0.150114)
			(stroke
				(width 0.1)
				(type default)
			)
			(layer "F.Fab")
		)
		(fp_line
			(start -0.299974 -0.150114)
			(end 0.299974 -0.150114)
			(stroke
				(width 0.1)
				(type default)
			)
			(layer "F.Fab")
		)
		(fp_line
			(start 0.299974 -0.150114)
			(end 0.299974 0.150114)
			(stroke
				(width 0.1)
				(type default)
			)
			(layer "F.Fab")
		)
		(pad "1" smd rect
			(at -0.2667 0 270)
			(size 0.3048 0.381)
			(layers "F.Cu" "F.Mask" "F.Paste")
			(net "P5E_CPU0_PE4_TX_C_DN<9>")
		)
		(pad "2" smd rect
			(at 0.2667 0 270)
			(size 0.3048 0.381)
			(layers "F.Cu" "F.Mask" "F.Paste")
			(net "P5E_CPU0_PE4_TX_DN<9>")
		)
	)
	(footprint ""
		(layer "F.Cu")
		(at 418.90188 -156.632148 90)
		(property "Reference" "PC175"
			(at 0 0 90)
			(layer "F.SilkS")
			(hide yes)
			(effects
				(font
					(size 1.27 1.27)
				)
			)
		)
		(property "Value" ""
			(at 0 0 90)
			(layer "F.Fab")
			(effects
				(font
					(size 1.27 1.27)
				)
			)
		)
		(duplicate_pad_numbers_are_jumpers no)
		(fp_line
			(start 0.7874 -0.4064)
			(end 0.7874 0.4064)
			(stroke
				(width 0.1524)
				(type default)
			)
			(layer "F.SilkS")
		)
		(fp_line
			(start -0.7874 -0.4064)
			(end 0.7874 -0.4064)
			(stroke
				(width 0.1524)
				(type default)
			)
			(layer "F.SilkS")
		)
		(fp_line
			(start 0.7874 0.4064)
			(end -0.7874 0.4064)
			(stroke
				(width 0.1524)
				(type default)
			)
			(layer "F.SilkS")
		)
		(fp_line
			(start -0.7874 0.4064)
			(end -0.7874 -0.4064)
			(stroke
				(width 0.1524)
				(type default)
			)
			(layer "F.SilkS")
		)
		(fp_line
			(start -0.12065 -0.305054)
			(end -0.12065 -0.2794)
			(stroke
				(width 0.1)
				(type default)
			)
			(layer "F.Fab")
		)
		(fp_line
			(start -0.67945 -0.305054)
			(end -0.12065 -0.305054)
			(stroke
				(width 0.1)
				(type default)
			)
			(layer "F.Fab")
		)
		(fp_line
			(start 0.67945 -0.3048)
			(end 0.67945 0.3048)
			(stroke
				(width 0.1)
				(type default)
			)
			(layer "F.Fab")
		)
		(fp_line
			(start 0.12065 -0.3048)
			(end 0.67945 -0.3048)
			(stroke
				(width 0.1)
				(type default)
			)
			(layer "F.Fab")
		)
		(fp_line
			(start 0.12065 -0.2794)
			(end 0.12065 -0.3048)
			(stroke
				(width 0.1)
				(type default)
			)
			(layer "F.Fab")
		)
		(fp_line
			(start -0.12065 -0.2794)
			(end 0.12065 -0.2794)
			(stroke
				(width 0.1)
				(type default)
			)
			(layer "F.Fab")
		)
		(fp_line
			(start 0.120396 0.2794)
			(end -0.12065 0.2794)
			(stroke
				(width 0.1)
				(type default)
			)
			(layer "F.Fab")
		)
		(fp_line
			(start -0.12065 0.2794)
			(end -0.12065 0.3048)
			(stroke
				(width 0.1)
				(type default)
			)
			(layer "F.Fab")
		)
		(fp_line
			(start 0.67945 0.3048)
			(end 0.120396 0.3048)
			(stroke
				(width 0.1)
				(type default)
			)
			(layer "F.Fab")
		)
		(fp_line
			(start 0.120396 0.3048)
			(end 0.120396 0.2794)
			(stroke
				(width 0.1)
				(type default)
			)
			(layer "F.Fab")
		)
		(fp_line
			(start -0.12065 0.3048)
			(end -0.67945 0.3048)
			(stroke
				(width 0.1)
				(type default)
			)
			(layer "F.Fab")
		)
		(fp_line
			(start -0.67945 0.3048)
			(end -0.67945 -0.305054)
			(stroke
				(width 0.1)
				(type default)
			)
			(layer "F.Fab")
		)
		(pad "1" smd circle
			(at -0.40005 0 90)
			(size 0 0)
			(layers "F.Cu" "F.Mask" "F.Paste")
			(net "PVCCFA_EHV_CPU0_VDD1")
		)
		(pad "2" smd circle
			(at 0.40005 0 90)
			(size 0 0)
			(layers "F.Cu" "F.Mask" "F.Paste")
			(net "GND")
		)
	)
)
